(kicad_pcb
	(version 20260206)
	(generator "pcbnew")
	(generator_version "10.0")
	(general
		(thickness 1.6)
		(legacy_teardrops no)
	)
	(paper "A4")
	(title_block
		(title "pdpb — Lightning_PDPB_BRD.brd")
		(comment 1 "Lightning (Wiwynn / Facebook NVMe JBOF) / footprints 394-400 of 1140")
	)
	(layers
		(0 "F.Cu" signal "TOP")
		(4 "In1.Cu" signal "L2GND")
		(6 "In2.Cu" signal "L3")
		(8 "In3.Cu" signal "L4VCC")
		(10 "In4.Cu" signal "L5VCC")
		(12 "In5.Cu" signal "L6")
		(14 "In6.Cu" signal "L7GND")
		(2 "B.Cu" signal "BOTTOM")
		(9 "F.Adhes" user "F.Adhesive")
		(11 "B.Adhes" user "B.Adhesive")
		(13 "F.Paste" user "Package Geometry/Pastemask Top")
		(15 "B.Paste" user "Package Geometry/Pastemask Bottom")
		(5 "F.SilkS" user "Ref Des/Silkscreen Top")
		(7 "B.SilkS" user "Ref Des/Silkscreen Bottom")
		(1 "F.Mask" user "Board Geometry/Soldermask Top")
		(3 "B.Mask" user "Board Geometry/Soldermask Bottom")
		(17 "Dwgs.User" user "User.Drawings")
		(19 "Cmts.User" user "User.Comments")
		(21 "Eco1.User" user "User.Eco1")
		(23 "Eco2.User" user "User.Eco2")
		(25 "Edge.Cuts" user "Board Geometry/Outline")
		(27 "Margin" user)
		(31 "F.CrtYd" user "Package Geometry/Place Bound Top")
		(29 "B.CrtYd" user "Package Geometry/Place Bound Bottom")
		(35 "F.Fab" user "Ref Des/Assembly Top")
		(33 "B.Fab" user "Ref Des/Assembly Bottom")
	)
	(footprint ""
		(layer "F.Cu")
		(at 37.2364 -91.5162 180)
		(property "Reference" "PC1197"
			(at 0 0 180)
			(layer "F.SilkS")
			(hide yes)
			(effects
				(font
					(size 1.27 1.27)
				)
			)
		)
		(property "Value" "SCD1U50V3KX-GP"
			(at 0 -2.8194 180)
			(unlocked yes)
			(layer "F.Fab")
			(hide yes)
			(effects
				(font
					(size 1.016 1.016)
					(thickness 0.1524)
				)
			)
		)
		(property "Device Type" "C603H36"
			(at 0 -4.3434 180)
			(unlocked yes)
			(layer "F.Fab")
			(hide yes)
			(effects
				(font
					(size 1.016 1.016)
					(thickness 0.1524)
				)
			)
		)
		(duplicate_pad_numbers_are_jumpers no)
		(fp_line
			(start 0.508 0)
			(end -0.508 0)
			(stroke
				(width 0.2032)
				(type default)
			)
			(layer "F.SilkS")
		)
		(fp_rect
			(start -0.5842 1.3335)
			(end 0.5842 -1.3335)
			(stroke
				(width 0)
				(type default)
			)
			(fill no)
			(layer "F.CrtYd")
		)
		(fp_rect
			(start -0.5842 1.3335)
			(end 0.5842 -1.3335)
			(stroke
				(width 0)
				(type default)
			)
			(fill no)
			(layer "F.Fab")
		)
		(pad "1" smd custom
			(at 0 -0.762 180)
			(size 0.2159 0.2159)
			(layers "F.Cu" "F.Mask" "F.Paste")
			(net "P12V_SSD9")
			(options
				(clearance outline)
				(anchor circle)
			)
			(primitives
				(gr_poly
					(pts
						(arc
							(start -0.3302 -0.4318)
							(mid -0.402042 -0.402042)
							(end -0.4318 -0.3302)
						)
						(arc
							(start -0.4318 0.3302)
							(mid -0.402042 0.402042)
							(end -0.3302 0.4318)
						)
						(arc
							(start 0.3302 0.4318)
							(mid 0.402042 0.402042)
							(end 0.4318 0.3302)
						)
						(arc
							(start 0.4318 -0.3302)
							(mid 0.402042 -0.402042)
							(end 0.3302 -0.4318)
						)
					)
					(width 0)
					(fill yes)
				)
			)
		)
		(pad "2" smd custom
			(at 0 0.762 180)
			(size 0.2159 0.2159)
			(layers "F.Cu" "F.Mask" "F.Paste")
			(net "GND")
			(options
				(clearance outline)
				(anchor circle)
			)
			(primitives
				(gr_poly
					(pts
						(arc
							(start -0.3302 -0.4318)
							(mid -0.402042 -0.402042)
							(end -0.4318 -0.3302)
						)
						(arc
							(start -0.4318 0.3302)
							(mid -0.402042 0.402042)
							(end -0.3302 0.4318)
						)
						(arc
							(start 0.3302 0.4318)
							(mid 0.402042 0.402042)
							(end 0.4318 0.3302)
						)
						(arc
							(start 0.4318 -0.3302)
							(mid 0.402042 -0.402042)
							(end 0.3302 -0.4318)
						)
					)
					(width 0)
					(fill yes)
				)
			)
		)
	)
	(footprint ""
		(layer "F.Cu")
		(at 228.981 -428.752)
		(property "Reference" "PR9083"
			(at 0 0 0)
			(layer "F.SilkS")
			(hide yes)
			(effects
				(font
					(size 1.27 1.27)
				)
			)
		)
		(property "Value" "2D2R3-1-U-GP"
			(at -0.0254 -2.5146 0)
			(unlocked yes)
			(layer "F.Fab")
			(hide yes)
			(effects
				(font
					(size 1.016 1.016)
					(thickness 0.1524)
				)
			)
		)
		(property "Device Type" "R603H22"
			(at -0.0254 -4.0386 0)
			(unlocked yes)
			(layer "F.Fab")
			(hide yes)
			(effects
				(font
					(size 1.016 1.016)
					(thickness 0.1524)
				)
			)
		)
		(duplicate_pad_numbers_are_jumpers no)
		(fp_line
			(start -0.4826 0)
			(end -0.2032 0)
			(stroke
				(width 0.2032)
				(type default)
			)
			(layer "F.SilkS")
		)
		(fp_line
			(start 0.2032 0)
			(end 0.4826 0)
			(stroke
				(width 0.2032)
				(type default)
			)
			(layer "F.SilkS")
		)
		(fp_rect
			(start -0.5842 1.3335)
			(end 0.5842 -1.3335)
			(stroke
				(width 0)
				(type default)
			)
			(fill no)
			(layer "F.CrtYd")
		)
		(fp_rect
			(start -0.5842 1.3335)
			(end 0.5842 -1.3335)
			(stroke
				(width 0)
				(type default)
			)
			(fill no)
			(layer "F.Fab")
		)
		(pad "1" smd custom
			(at 0 -0.762)
			(size 0.2159 0.2159)
			(layers "F.Cu" "F.Mask" "F.Paste")
			(net "P3V3_VCC")
			(options
				(clearance outline)
				(anchor circle)
			)
			(primitives
				(gr_poly
					(pts
						(arc
							(start -0.3302 -0.4318)
							(mid -0.402042 -0.402042)
							(end -0.4318 -0.3302)
						)
						(arc
							(start -0.4318 0.3302)
							(mid -0.402042 0.402042)
							(end -0.3302 0.4318)
						)
						(arc
							(start 0.3302 0.4318)
							(mid 0.402042 0.402042)
							(end 0.4318 0.3302)
						)
						(arc
							(start 0.4318 -0.3302)
							(mid 0.402042 -0.402042)
							(end 0.3302 -0.4318)
						)
					)
					(width 0)
					(fill yes)
				)
			)
		)
		(pad "2" smd custom
			(at 0 0.762)
			(size 0.2159 0.2159)
			(layers "F.Cu" "F.Mask" "F.Paste")
			(net "P12V")
			(options
				(clearance outline)
				(anchor circle)
			)
			(primitives
				(gr_poly
					(pts
						(arc
							(start -0.3302 -0.4318)
							(mid -0.402042 -0.402042)
							(end -0.4318 -0.3302)
						)
						(arc
							(start -0.4318 0.3302)
							(mid -0.402042 0.402042)
							(end -0.3302 0.4318)
						)
						(arc
							(start 0.3302 0.4318)
							(mid 0.402042 0.402042)
							(end 0.4318 0.3302)
						)
						(arc
							(start 0.4318 -0.3302)
							(mid 0.402042 -0.402042)
							(end 0.3302 -0.4318)
						)
					)
					(width 0)
					(fill yes)
				)
			)
		)
	)
	(footprint ""
		(layer "F.Cu")
		(at 98.806 -116.586 90)
		(property "Reference" "R9430"
			(at 0 0 90)
			(layer "F.SilkS")
			(hide yes)
			(effects
				(font
					(size 1.27 1.27)
				)
			)
		)
		(property "Value" "4K7R2J-2-GP"
			(at 0.064008 -3.993896 90)
			(unlocked yes)
			(layer "F.Fab")
			(hide yes)
			(effects
				(font
					(size 1.016 1.016)
					(thickness 0.1524)
				)
			)
		)
		(property "Device Type" "R402H16"
			(at 0.064008 -5.517896 90)
			(unlocked yes)
			(layer "F.Fab")
			(hide yes)
			(effects
				(font
					(size 1.016 1.016)
					(thickness 0.1524)
				)
			)
		)
		(duplicate_pad_numbers_are_jumpers no)
		(fp_line
			(start 0.508 -0.9398)
			(end -0.508 -0.9398)
			(stroke
				(width 0.1524)
				(type default)
			)
			(layer "F.SilkS")
		)
		(fp_line
			(start -0.508 -0.9398)
			(end -0.508 0.9398)
			(stroke
				(width 0.1524)
				(type default)
			)
			(layer "F.SilkS")
		)
		(fp_rect
			(start -0.508 0.9398)
			(end 0.508 -0.9398)
			(stroke
				(width 0)
				(type default)
			)
			(fill no)
			(layer "F.CrtYd")
		)
		(fp_rect
			(start -0.508 0.9398)
			(end 0.508 -0.9398)
			(stroke
				(width 0)
				(type default)
			)
			(fill no)
			(layer "F.Fab")
		)
		(pad "1" smd custom
			(at 0 -0.4445 90)
			(size 0.1397 0.1397)
			(layers "F.Cu" "F.Mask" "F.Paste")
			(net "P3V3")
			(options
				(clearance outline)
				(anchor circle)
			)
			(primitives
				(gr_poly
					(pts
						(arc
							(start -0.1778 -0.2794)
							(mid -0.249642 -0.249642)
							(end -0.2794 -0.1778)
						)
						(arc
							(start -0.2794 0.1778)
							(mid -0.249642 0.249642)
							(end -0.1778 0.2794)
						)
						(arc
							(start 0.1778 0.2794)
							(mid 0.249642 0.249642)
							(end 0.2794 0.1778)
						)
						(arc
							(start 0.2794 -0.1778)
							(mid 0.249642 -0.249642)
							(end 0.1778 -0.2794)
						)
					)
					(width 0)
					(fill yes)
				)
			)
		)
		(pad "2" smd custom
			(at 0 0.4445 90)
			(size 0.1397 0.1397)
			(layers "F.Cu" "F.Mask" "F.Paste")
			(net "SSD_PRSNT_NET8")
			(options
				(clearance outline)
				(anchor circle)
			)
			(primitives
				(gr_poly
					(pts
						(arc
							(start -0.1778 -0.2794)
							(mid -0.249642 -0.249642)
							(end -0.2794 -0.1778)
						)
						(arc
							(start -0.2794 0.1778)
							(mid -0.249642 0.249642)
							(end -0.1778 0.2794)
						)
						(arc
							(start 0.1778 0.2794)
							(mid 0.249642 0.249642)
							(end 0.2794 0.1778)
						)
						(arc
							(start 0.2794 -0.1778)
							(mid 0.249642 -0.249642)
							(end 0.1778 -0.2794)
						)
					)
					(width 0)
					(fill yes)
				)
			)
		)
	)
	(footprint ""
		(layer "F.Cu")
		(at 90.17 -318.643)
		(property "Reference" "R9610"
			(at 0 0 0)
			(layer "F.SilkS")
			(hide yes)
			(effects
				(font
					(size 1.27 1.27)
				)
			)
		)
		(property "Value" "10R2F-L-GP"
			(at 0.064008 -3.993896 0)
			(unlocked yes)
			(layer "F.Fab")
			(hide yes)
			(effects
				(font
					(size 1.016 1.016)
					(thickness 0.1524)
				)
			)
		)
		(property "Device Type" "R402H14"
			(at 0.064008 -5.517896 0)
			(unlocked yes)
			(layer "F.Fab")
			(hide yes)
			(effects
				(font
					(size 1.016 1.016)
					(thickness 0.1524)
				)
			)
		)
		(duplicate_pad_numbers_are_jumpers no)
		(fp_line
			(start -0.508 -0.9398)
			(end -0.508 0.9398)
			(stroke
				(width 0.1524)
				(type default)
			)
			(layer "F.SilkS")
		)
		(fp_line
			(start 0.508 -0.9398)
			(end -0.508 -0.9398)
			(stroke
				(width 0.1524)
				(type default)
			)
			(layer "F.SilkS")
		)
		(fp_rect
			(start -0.508 0.9398)
			(end 0.508 -0.9398)
			(stroke
				(width 0)
				(type default)
			)
			(fill no)
			(layer "F.CrtYd")
		)
		(fp_rect
			(start -0.508 0.9398)
			(end 0.508 -0.9398)
			(stroke
				(width 0)
				(type default)
			)
			(fill no)
			(layer "F.Fab")
		)
		(pad "1" smd custom
			(at 0 -0.4445)
			(size 0.1397 0.1397)
			(layers "F.Cu" "F.Mask" "F.Paste")
			(net "SSD_PRSNT_NET11")
			(options
				(clearance outline)
				(anchor circle)
			)
			(primitives
				(gr_poly
					(pts
						(arc
							(start -0.1778 -0.2794)
							(mid -0.249642 -0.249642)
							(end -0.2794 -0.1778)
						)
						(arc
							(start -0.2794 0.1778)
							(mid -0.249642 0.249642)
							(end -0.1778 0.2794)
						)
						(arc
							(start 0.1778 0.2794)
							(mid 0.249642 0.249642)
							(end 0.2794 0.1778)
						)
						(arc
							(start 0.2794 -0.1778)
							(mid 0.249642 -0.249642)
							(end 0.1778 -0.2794)
						)
					)
					(width 0)
					(fill yes)
				)
			)
		)
		(pad "2" smd custom
			(at 0 0.4445)
			(size 0.1397 0.1397)
			(layers "F.Cu" "F.Mask" "F.Paste")
			(net "SSD_PRSNT11")
			(options
				(clearance outline)
				(anchor circle)
			)
			(primitives
				(gr_poly
					(pts
						(arc
							(start -0.1778 -0.2794)
							(mid -0.249642 -0.249642)
							(end -0.2794 -0.1778)
						)
						(arc
							(start -0.2794 0.1778)
							(mid -0.249642 0.249642)
							(end -0.1778 0.2794)
						)
						(arc
							(start 0.1778 0.2794)
							(mid 0.249642 0.249642)
							(end 0.2794 0.1778)
						)
						(arc
							(start 0.2794 -0.1778)
							(mid 0.249642 -0.249642)
							(end 0.1778 -0.2794)
						)
					)
					(width 0)
					(fill yes)
				)
			)
		)
	)
	(footprint ""
		(layer "F.Cu")
		(at 36.6776 -212.8774 180)
		(property "Reference" "C394"
			(at 0 0 180)
			(layer "F.SilkS")
			(hide yes)
			(effects
				(font
					(size 1.27 1.27)
				)
			)
		)
		(property "Value" "SCD1U25V2KX-2-GP"
			(at 1.1811 -2.7051 180)
			(unlocked yes)
			(layer "F.Fab")
			(hide yes)
			(effects
				(font
					(size 1.016 1.016)
					(thickness 0.1524)
				)
			)
		)
		(property "Device Type" "C402H22"
			(at 1.1811 -4.2291 180)
			(unlocked yes)
			(layer "F.Fab")
			(hide yes)
			(effects
				(font
					(size 1.016 1.016)
					(thickness 0.1524)
				)
			)
		)
		(duplicate_pad_numbers_are_jumpers no)
		(fp_rect
			(start -0.4318 0.9525)
			(end 0.4318 -0.9525)
			(stroke
				(width 0)
				(type default)
			)
			(fill no)
			(layer "F.CrtYd")
		)
		(fp_rect
			(start -0.4318 0.9525)
			(end 0.4318 -0.9525)
			(stroke
				(width 0)
				(type default)
			)
			(fill no)
			(layer "F.Fab")
		)
		(pad "1" smd custom
			(at 0 -0.4445 180)
			(size 0.1524 0.1524)
			(layers "F.Cu" "F.Mask" "F.Paste")
			(net "P12V")
			(options
				(clearance outline)
				(anchor circle)
			)
			(primitives
				(gr_poly
					(pts
						(arc
							(start 0.3048 -0.2032)
							(mid 0.275042 -0.275042)
							(end 0.2032 -0.3048)
						)
						(arc
							(start -0.2032 -0.3048)
							(mid -0.275042 -0.275042)
							(end -0.3048 -0.2032)
						)
						(arc
							(start -0.3048 0.2032)
							(mid -0.275042 0.275042)
							(end -0.2032 0.3048)
						)
						(arc
							(start 0.2032 0.3048)
							(mid 0.275042 0.275042)
							(end 0.3048 0.2032)
						)
					)
					(width 0)
					(fill yes)
				)
			)
		)
		(pad "2" smd custom
			(at 0 0.4445 180)
			(size 0.1524 0.1524)
			(layers "F.Cu" "F.Mask" "F.Paste")
			(net "SW_SSD12_N")
			(options
				(clearance outline)
				(anchor circle)
			)
			(primitives
				(gr_poly
					(pts
						(arc
							(start 0.3048 -0.2032)
							(mid 0.275042 -0.275042)
							(end 0.2032 -0.3048)
						)
						(arc
							(start -0.2032 -0.3048)
							(mid -0.275042 -0.275042)
							(end -0.3048 -0.2032)
						)
						(arc
							(start -0.3048 0.2032)
							(mid -0.275042 0.275042)
							(end -0.2032 0.3048)
						)
						(arc
							(start 0.2032 0.3048)
							(mid 0.275042 0.275042)
							(end 0.3048 0.2032)
						)
					)
					(width 0)
					(fill yes)
				)
			)
		)
	)
	(footprint ""
		(layer "F.Cu")
		(at 209.296 -194.183 180)
		(property "Reference" "Q11"
			(at 0 0 180)
			(layer "F.SilkS")
			(hide yes)
			(effects
				(font
					(size 1.27 1.27)
				)
			)
		)
		(property "Value" "2N7002A-7-GP"
			(at 0.127 -8.9662 180)
			(unlocked yes)
			(layer "F.Fab")
			(hide yes)
			(effects
				(font
					(size 1.016 1.016)
					(thickness 0.1524)
				)
			)
		)
		(property "Device Type" "SOT23DGS2D4H48"
			(at 0.127 -10.4902 180)
			(unlocked yes)
			(layer "F.Fab")
			(hide yes)
			(effects
				(font
					(size 1.016 1.016)
					(thickness 0.1524)
				)
			)
		)
		(duplicate_pad_numbers_are_jumpers no)
		(fp_line
			(start 1.651 1.778)
			(end 1.651 -1.778)
			(stroke
				(width 0.1524)
				(type default)
			)
			(layer "F.SilkS")
		)
		(fp_line
			(start 1.651 -1.778)
			(end -1.651 -1.778)
			(stroke
				(width 0.1524)
				(type default)
			)
			(layer "F.SilkS")
		)
		(fp_line
			(start -1.651 1.778)
			(end 1.651 1.778)
			(stroke
				(width 0.1524)
				(type default)
			)
			(layer "F.SilkS")
		)
		(fp_line
			(start -1.651 -1.778)
			(end -1.651 1.778)
			(stroke
				(width 0.1524)
				(type default)
			)
			(layer "F.SilkS")
		)
		(fp_poly
			(pts
				(xy -1.778 1.8796) (xy -1.778 -1.8796) (xy 1.778 -1.8796) (xy 1.778 1.8796)
			)
			(stroke
				(width 0)
				(type default)
			)
			(fill no)
			(layer "F.CrtYd")
		)
		(fp_poly
			(pts
				(xy -1.778 1.8796) (xy -1.778 -1.8796) (xy 1.778 -1.8796) (xy 1.778 1.8796)
			)
			(stroke
				(width 0)
				(type default)
			)
			(fill no)
			(layer "F.Fab")
		)
		(pad "D" smd custom
			(at 0 -0.9525 180)
			(size 0.1905 0.1905)
			(layers "F.Cu" "F.Mask" "F.Paste")
			(net "SW_SSD3_R")
			(options
				(clearance outline)
				(anchor circle)
			)
			(primitives
				(gr_poly
					(pts
						(arc
							(start -0.1778 0.5715)
							(mid -0.321484 0.511984)
							(end -0.381 0.3683)
						)
						(arc
							(start -0.381 -0.3683)
							(mid -0.321484 -0.511984)
							(end -0.1778 -0.5715)
						)
						(arc
							(start 0.1778 -0.5715)
							(mid 0.321484 -0.511984)
							(end 0.381 -0.3683)
						)
						(arc
							(start 0.381 0.3683)
							(mid 0.321484 0.511984)
							(end 0.1778 0.5715)
						)
					)
					(width 0)
					(fill yes)
				)
			)
		)
		(pad "G" smd custom
			(at -0.98425 0.9525 180)
			(size 0.1905 0.1905)
			(layers "F.Cu" "F.Mask" "F.Paste")
			(net "SSD3_PWREN")
			(options
				(clearance outline)
				(anchor circle)
			)
			(primitives
				(gr_poly
					(pts
						(arc
							(start -0.1778 0.5715)
							(mid -0.321484 0.511984)
							(end -0.381 0.3683)
						)
						(arc
							(start -0.381 -0.3683)
							(mid -0.321484 -0.511984)
							(end -0.1778 -0.5715)
						)
						(arc
							(start 0.1778 -0.5715)
							(mid 0.321484 -0.511984)
							(end 0.381 -0.3683)
						)
						(arc
							(start 0.381 0.3683)
							(mid 0.321484 0.511984)
							(end 0.1778 0.5715)
						)
					)
					(width 0)
					(fill yes)
				)
			)
		)
		(pad "S" smd custom
			(at 0.98425 0.9525 180)
			(size 0.1905 0.1905)
			(layers "F.Cu" "F.Mask" "F.Paste")
			(net "GND")
			(options
				(clearance outline)
				(anchor circle)
			)
			(primitives
				(gr_poly
					(pts
						(arc
							(start -0.1778 0.5715)
							(mid -0.321484 0.511984)
							(end -0.381 0.3683)
						)
						(arc
							(start -0.381 -0.3683)
							(mid -0.321484 -0.511984)
							(end -0.1778 -0.5715)
						)
						(arc
							(start 0.1778 -0.5715)
							(mid 0.321484 -0.511984)
							(end 0.381 -0.3683)
						)
						(arc
							(start 0.381 0.3683)
							(mid 0.321484 0.511984)
							(end 0.1778 0.5715)
						)
					)
					(width 0)
					(fill yes)
				)
			)
		)
	)
	(footprint ""
		(layer "F.Cu")
		(at 230.632 -449.199 -90)
		(property "Reference" "R9783"
			(at 0 0 270)
			(layer "F.SilkS")
			(hide yes)
			(effects
				(font
					(size 1.27 1.27)
				)
			)
		)
		(property "Value" "0R2J-2-GP"
			(at 0.064008 -3.993896 270)
			(unlocked yes)
			(layer "F.Fab")
			(hide yes)
			(effects
				(font
					(size 1.016 1.016)
					(thickness 0.1524)
				)
			)
		)
		(property "Device Type" "R402H16"
			(at 0.064008 -5.517896 270)
			(unlocked yes)
			(layer "F.Fab")
			(hide yes)
			(effects
				(font
					(size 1.016 1.016)
					(thickness 0.1524)
				)
			)
		)
		(duplicate_pad_numbers_are_jumpers no)
		(fp_line
			(start -0.508 -0.9398)
			(end -0.508 0.9398)
			(stroke
				(width 0.1524)
				(type default)
			)
			(layer "F.SilkS")
		)
		(fp_line
			(start 0.508 -0.9398)
			(end -0.508 -0.9398)
			(stroke
				(width 0.1524)
				(type default)
			)
			(layer "F.SilkS")
		)
		(fp_rect
			(start -0.508 0.9398)
			(end 0.508 -0.9398)
			(stroke
				(width 0)
				(type default)
			)
			(fill no)
			(layer "F.CrtYd")
		)
		(fp_rect
			(start -0.508 0.9398)
			(end 0.508 -0.9398)
			(stroke
				(width 0)
				(type default)
			)
			(fill no)
			(layer "F.Fab")
		)
		(pad "1" smd custom
			(at 0 -0.4445 270)
			(size 0.1397 0.1397)
			(layers "F.Cu" "F.Mask" "F.Paste")
			(net "SSD_ACT_DR0_R")
			(options
				(clearance outline)
				(anchor circle)
			)
			(primitives
				(gr_poly
					(pts
						(arc
							(start -0.1778 -0.2794)
							(mid -0.249642 -0.249642)
							(end -0.2794 -0.1778)
						)
						(arc
							(start -0.2794 0.1778)
							(mid -0.249642 0.249642)
							(end -0.1778 0.2794)
						)
						(arc
							(start 0.1778 0.2794)
							(mid 0.249642 0.249642)
							(end 0.2794 0.1778)
						)
						(arc
							(start 0.2794 -0.1778)
							(mid 0.249642 -0.249642)
							(end 0.1778 -0.2794)
						)
					)
					(width 0)
					(fill yes)
				)
			)
		)
		(pad "2" smd custom
			(at 0 0.4445 270)
			(size 0.1397 0.1397)
			(layers "F.Cu" "F.Mask" "F.Paste")
			(net "SSD_ACT_DR0")
			(options
				(clearance outline)
				(anchor circle)
			)
			(primitives
				(gr_poly
					(pts
						(arc
							(start -0.1778 -0.2794)
							(mid -0.249642 -0.249642)
							(end -0.2794 -0.1778)
						)
						(arc
							(start -0.2794 0.1778)
							(mid -0.249642 0.249642)
							(end -0.1778 0.2794)
						)
						(arc
							(start 0.1778 0.2794)
							(mid 0.249642 0.249642)
							(end 0.2794 0.1778)
						)
						(arc
							(start 0.2794 -0.1778)
							(mid 0.249642 -0.249642)
							(end 0.1778 -0.2794)
						)
					)
					(width 0)
					(fill yes)
				)
			)
		)
	)
)
